FILE_TYPE = CONNECTIVITY;
{Allegro Design Entry HDL 17.4-2019 S026 (4007227) 1/17/2022}
"PAGE_NUMBER" = 354;
0"NC";
1"P5E_CPU1_P1_TX_DP<15:8>";
2"P5E_CPU1_P1_TX_DN<15:8>";
3"P5E_CPU1_P1_TX_DP<7:0>";
4"P5E_CPU1_P1_TX_C_DN<7:0>";
5"P5E_CPU1_P1_TX_C_DP<7:0>";
6"P5E_CPU1_P1_TX_C_DP<15:8>";
7"P5E_CPU1_P1_TX_C_DN<15:8>";
8"P5E_CPU1_P1_TX_DN<7:0>";
9"P5E_CPU1_P2_TX_DP<15:8>";
10"P5E_CPU1_P2_TX_C_DN<15:8>";
11"P5E_CPU1_P2_TX_C_DP<7:0>";
12"P5E_CPU1_P2_TX_DP<7:0>";
13"P5E_CPU1_P2_TX_DN<15:8>";
14"P5E_CPU1_P2_TX_C_DP<15:8>";
15"P5E_CPU1_P2_TX_C_DN<7:0>";
16"P5E_CPU1_P2_TX_DN<7:0>";
17"P5E_CPU1_P2_TX_DN<7>";
18"P5E_CPU1_P2_TX_DP<6>";
19"P5E_CPU1_P2_TX_C_DN<15>";
20"P5E_CPU1_P2_TX_DP<13>";
21"P5E_CPU1_P1_TX_C_DP<11>";
22"P5E_CPU1_P1_TX_C_DN<10>";
23"P5E_CPU1_P1_TX_C_DP<9>";
24"P5E_CPU1_P1_TX_C_DP<7>";
25"P5E_CPU1_P1_TX_DN<4>";
26"P5E_CPU1_P1_TX_DP<1>";
27"P5E_CPU1_P1_TX_DN<0>";
28"P5E_CPU1_P1_TX_C_DP<2>";
29"P5E_CPU1_P1_TX_DP<8>";
30"P5E_CPU1_P2_TX_DN<5>";
31"P5E_CPU1_P2_TX_DN<2>";
32"P5E_CPU1_P2_TX_DN<1>";
33"P5E_CPU1_P2_TX_DN<3>";
34"P5E_CPU1_P2_TX_DN<0>";
35"P5E_CPU1_P2_TX_DP<1>";
36"P5E_CPU1_P2_TX_DP<2>";
37"P5E_CPU1_P2_TX_DP<0>";
38"P5E_CPU1_P2_TX_DP<5>";
39"P5E_CPU1_P2_TX_DN<15>";
40"P5E_CPU1_P2_TX_DN<13>";
41"P5E_CPU1_P2_TX_DN<14>";
42"P5E_CPU1_P2_TX_DN<10>";
43"P5E_CPU1_P2_TX_DN<9>";
44"P5E_CPU1_P2_TX_DN<11>";
45"P5E_CPU1_P2_TX_DN<8>";
46"P5E_CPU1_P2_TX_DP<8>";
47"P5E_CPU1_P2_TX_DP<15>";
48"P5E_CPU1_P2_TX_C_DN<3>";
49"P5E_CPU1_P2_TX_C_DP<4>";
50"P5E_CPU1_P2_TX_C_DP<2>";
51"P5E_CPU1_P2_TX_C_DP<3>";
52"P5E_CPU1_P2_TX_C_DP<0>";
53"P5E_CPU1_P2_TX_C_DN<4>";
54"P5E_CPU1_P2_TX_C_DN<5>";
55"P5E_CPU1_P2_TX_C_DN<6>";
56"P5E_CPU1_P2_TX_C_DN<7>";
57"P5E_CPU1_P2_TX_C_DP<5>";
58"P5E_CPU1_P2_TX_C_DP<7>";
59"P5E_CPU1_P2_TX_C_DN<9>";
60"P5E_CPU1_P2_TX_C_DN<8>";
61"P5E_CPU1_P2_TX_C_DN<10>";
62"P5E_CPU1_P2_TX_C_DN<11>";
63"P5E_CPU1_P2_TX_C_DP<8>";
64"P5E_CPU1_P2_TX_C_DN<14>";
65"P5E_CPU1_P2_TX_C_DP<15>";
66"P5E_CPU1_P2_TX_C_DP<14>";
67"P5E_CPU1_P2_TX_C_DP<13>";
68"P5E_CPU1_P2_TX_C_DP<1>";
69"P5E_CPU1_P2_TX_C_DN<0>";
70"P5E_CPU1_P2_TX_C_DP<11>";
71"P5E_CPU1_P2_TX_DN<6>";
72"P5E_CPU1_P2_TX_DP<10>";
73"P5E_CPU1_P2_TX_DN<4>";
74"P5E_CPU1_P2_TX_DP<4>";
75"P5E_CPU1_P2_TX_C_DN<1>";
76"P5E_CPU1_P2_TX_C_DP<10>";
77"P5E_CPU1_P2_TX_DP<9>";
78"P5E_CPU1_P2_TX_C_DP<9>";
79"P5E_CPU1_P2_TX_C_DN<2>";
80"P5E_CPU1_P2_TX_DP<3>";
81"P5E_CPU1_P2_TX_DP<12>";
82"P5E_CPU1_P2_TX_C_DP<12>";
83"P5E_CPU1_P2_TX_C_DN<12>";
84"P5E_CPU1_P2_TX_DN<12>";
85"P5E_CPU1_P2_TX_DP<11>";
86"P5E_CPU1_P2_TX_DP<7>";
87"P5E_CPU1_P2_TX_C_DP<6>";
88"P5E_CPU1_P2_TX_C_DN<13>";
89"P5E_CPU1_P2_TX_DP<14>";
90"P5E_CPU1_P1_TX_DN<2>";
91"P5E_CPU1_P1_TX_DP<0>";
92"P5E_CPU1_P1_TX_DP<4>";
93"P5E_CPU1_P1_TX_DP<3>";
94"P5E_CPU1_P1_TX_DP<2>";
95"P5E_CPU1_P1_TX_DN<1>";
96"P5E_CPU1_P1_TX_DN<7>";
97"P5E_CPU1_P1_TX_DN<5>";
98"P5E_CPU1_P1_TX_DP<5>";
99"P5E_CPU1_P1_TX_DP<6>";
100"P5E_CPU1_P1_TX_DN<3>";
101"P5E_CPU1_P1_TX_DN<6>";
102"P5E_CPU1_P1_TX_C_DP<0>";
103"P5E_CPU1_P1_TX_C_DN<2>";
104"P5E_CPU1_P1_TX_C_DN<1>";
105"P5E_CPU1_P1_TX_C_DN<0>";
106"P5E_CPU1_P1_TX_C_DN<3>";
107"P5E_CPU1_P1_TX_C_DP<1>";
108"P5E_CPU1_P1_TX_C_DP<3>";
109"P5E_CPU1_P1_TX_C_DN<4>";
110"P5E_CPU1_P1_TX_C_DN<7>";
111"P5E_CPU1_P1_TX_C_DN<5>";
112"P5E_CPU1_P1_TX_DN<10>";
113"P5E_CPU1_P1_TX_DN<11>";
114"P5E_CPU1_P1_TX_DP<9>";
115"P5E_CPU1_P1_TX_DP<10>";
116"P5E_CPU1_P1_TX_DN<8>";
117"P5E_CPU1_P1_TX_DN<15>";
118"P5E_CPU1_P1_TX_DN<13>";
119"P5E_CPU1_P1_TX_C_DP<12>";
120"P5E_CPU1_P1_TX_C_DN<11>";
121"P5E_CPU1_P1_TX_C_DN<8>";
122"P5E_CPU1_P1_TX_C_DN<12>";
123"P5E_CPU1_P1_TX_C_DN<9>";
124"P5E_CPU1_P1_TX_C_DP<10>";
125"P5E_CPU1_P1_TX_C_DP<8>";
126"P5E_CPU1_P1_TX_C_DN<14>";
127"P5E_CPU1_P1_TX_C_DN<13>";
128"P5E_CPU1_P1_TX_C_DN<15>";
129"P5E_CPU1_P1_TX_C_DP<14>";
130"P5E_CPU1_P1_TX_C_DP<15>";
131"P5E_CPU1_P1_TX_C_DP<13>";
132"P5E_CPU1_P1_TX_C_DP<4>";
133"P5E_CPU1_P1_TX_C_DP<5>";
134"P5E_CPU1_P1_TX_C_DP<6>";
135"P5E_CPU1_P1_TX_C_DN<6>";
136"P5E_CPU1_P1_TX_DP<7>";
137"P5E_CPU1_P1_TX_DN<9>";
138"P5E_CPU1_P1_TX_DP<11>";
139"P5E_CPU1_P1_TX_DP<12>";
140"P5E_CPU1_P1_TX_DN<12>";
141"P5E_CPU1_P1_TX_DP<13>";
142"P5E_CPU1_P1_TX_DP<14>";
143"P5E_CPU1_P1_TX_DN<14>";
144"P5E_CPU1_P1_TX_DP<15>";
%"TAP"
"1","(2650,200)","2","standard","I109";
;
CDS_LIB"standard"
BODY_TYPE"PLUMBING"
HDL_TAP"TRUE";
"B \NAC \NWC"12;
"S \NAC"
BN"0"37;
%"TAP"
"1","(2650,400)","2","standard","I110";
;
CDS_LIB"standard"
BODY_TYPE"PLUMBING"
HDL_TAP"TRUE";
"B \NAC \NWC"12;
"S \NAC"
BN"1"35;
%"TAP"
"1","(2650,600)","2","standard","I111";
;
CDS_LIB"standard"
BODY_TYPE"PLUMBING"
HDL_TAP"TRUE";
"B \NAC \NWC"12;
"S \NAC"
BN"2"36;
%"TAP"
"1","(2650,800)","2","standard","I112";
;
CDS_LIB"standard"
BODY_TYPE"PLUMBING"
HDL_TAP"TRUE";
"B \NAC \NWC"12;
"S \NAC"
BN"3"80;
%"TAP"
"1","(2650,1000)","2","standard","I113";
;
CDS_LIB"standard"
BODY_TYPE"PLUMBING"
HDL_TAP"TRUE";
"B \NAC \NWC"12;
"S \NAC"
BN"4"74;
%"TAP"
"1","(2650,1200)","2","standard","I114";
;
CDS_LIB"standard"
BODY_TYPE"PLUMBING"
HDL_TAP"TRUE";
"B \NAC \NWC"12;
"S \NAC"
BN"5"38;
%"TAP"
"1","(2650,1400)","2","standard","I115";
;
CDS_LIB"standard"
BODY_TYPE"PLUMBING"
HDL_TAP"TRUE";
"B \NAC \NWC"12;
"S \NAC"
BN"6"18;
%"TAP"
"1","(2650,1600)","2","standard","I116";
;
CDS_LIB"standard"
BODY_TYPE"PLUMBING"
HDL_TAP"TRUE";
"B \NAC \NWC"12;
"S \NAC"
BN"7"86;
%"TAP"
"1","(2900,250)","2","standard","I117";
;
CDS_LIB"standard"
BODY_TYPE"PLUMBING"
HDL_TAP"TRUE";
"B \NAC \NWC"16;
"S \NAC"
BN"0"34;
%"TAP"
"1","(2900,450)","2","standard","I118";
;
CDS_LIB"standard"
BODY_TYPE"PLUMBING"
HDL_TAP"TRUE";
"B \NAC \NWC"16;
"S \NAC"
BN"1"32;
%"TAP"
"1","(2900,650)","2","standard","I119";
;
CDS_LIB"standard"
BODY_TYPE"PLUMBING"
HDL_TAP"TRUE";
"B \NAC \NWC"16;
"S \NAC"
BN"2"31;
%"TAP"
"1","(2900,850)","2","standard","I120";
;
CDS_LIB"standard"
BODY_TYPE"PLUMBING"
HDL_TAP"TRUE";
"B \NAC \NWC"16;
"S \NAC"
BN"3"33;
%"TAP"
"1","(2900,1050)","2","standard","I121";
;
CDS_LIB"standard"
BODY_TYPE"PLUMBING"
HDL_TAP"TRUE";
"B \NAC \NWC"16;
"S \NAC"
BN"4"73;
%"Q_CAP_DIFFBUS"
"2","(3625,200)","2","pure_quanta","I122";
;
LOCATION"C773"
$SEC"1"
CDS_SEC"1"
VALUE"DIFF BUS_0.22UF"
PIN_NAMES_ROTATE"TRUE"
CDS_LIB"pure_quanta"
CDS_LMAN_SYM_OUTLINE"-25,50,25,-50"
VOLTAGE"6.3V"
MATERIAL"X6S"
PACK_TYPE"C0201"
TOLERANCE"20%"
PART_NUMBER"SP_CH4221MEE01"
LOCATION"C773";
"2"
$PN"2"37;
"1"
$PN"1"52;
%"Q_CAP_DIFFBUS"
"2","(3625,250)","2","pure_quanta","I123";
;
LOCATION"C772"
$SEC"1"
CDS_SEC"1"
VALUE"DIFF BUS_0.22UF"
PIN_NAMES_ROTATE"TRUE"
CDS_LIB"pure_quanta"
CDS_LMAN_SYM_OUTLINE"-25,50,25,-50"
VOLTAGE"6.3V"
MATERIAL"X6S"
PACK_TYPE"C0201"
TOLERANCE"20%"
PART_NUMBER"SP_CH4221MEE01"
LOCATION"C772";
"2"
$PN"2"34;
"1"
$PN"1"69;
%"Q_CAP_DIFFBUS"
"2","(3625,400)","2","pure_quanta","I124";
;
LOCATION"C771"
$SEC"1"
CDS_SEC"1"
VALUE"DIFF BUS_0.22UF"
PIN_NAMES_ROTATE"TRUE"
CDS_LIB"pure_quanta"
CDS_LMAN_SYM_OUTLINE"-25,50,25,-50"
VOLTAGE"6.3V"
MATERIAL"X6S"
PACK_TYPE"C0201"
TOLERANCE"20%"
PART_NUMBER"SP_CH4221MEE01"
LOCATION"C771";
"2"
$PN"2"35;
"1"
$PN"1"68;
%"Q_CAP_DIFFBUS"
"2","(3625,450)","2","pure_quanta","I125";
;
LOCATION"C770"
$SEC"1"
CDS_SEC"1"
VALUE"DIFF BUS_0.22UF"
PIN_NAMES_ROTATE"TRUE"
CDS_LMAN_SYM_OUTLINE"-25,50,25,-50"
CDS_LIB"pure_quanta"
VOLTAGE"6.3V"
MATERIAL"X6S"
PACK_TYPE"C0201"
TOLERANCE"20%"
PART_NUMBER"SP_CH4221MEE01"
LOCATION"C770";
"2"
$PN"2"32;
"1"
$PN"1"75;
%"Q_CAP_DIFFBUS"
"2","(3625,600)","2","pure_quanta","I126";
;
LOCATION"C769"
$SEC"1"
CDS_SEC"1"
VALUE"DIFF BUS_0.22UF"
PIN_NAMES_ROTATE"TRUE"
CDS_LIB"pure_quanta"
CDS_LMAN_SYM_OUTLINE"-25,50,25,-50"
VOLTAGE"6.3V"
MATERIAL"X6S"
PACK_TYPE"C0201"
TOLERANCE"20%"
PART_NUMBER"SP_CH4221MEE01"
LOCATION"C769";
"2"
$PN"2"36;
"1"
$PN"1"50;
%"Q_CAP_DIFFBUS"
"2","(3625,650)","2","pure_quanta","I127";
;
LOCATION"C768"
$SEC"1"
CDS_SEC"1"
VALUE"DIFF BUS_0.22UF"
PIN_NAMES_ROTATE"TRUE"
CDS_LIB"pure_quanta"
CDS_LMAN_SYM_OUTLINE"-25,50,25,-50"
VOLTAGE"6.3V"
MATERIAL"X6S"
PACK_TYPE"C0201"
TOLERANCE"20%"
PART_NUMBER"SP_CH4221MEE01"
LOCATION"C768";
"2"
$PN"2"31;
"1"
$PN"1"79;
%"Q_CAP_DIFFBUS"
"2","(3625,800)","2","pure_quanta","I128";
;
LOCATION"C767"
$SEC"1"
CDS_SEC"1"
VALUE"DIFF BUS_0.22UF"
PIN_NAMES_ROTATE"TRUE"
CDS_LMAN_SYM_OUTLINE"-25,50,25,-50"
CDS_LIB"pure_quanta"
VOLTAGE"6.3V"
MATERIAL"X6S"
PACK_TYPE"C0201"
TOLERANCE"20%"
PART_NUMBER"SP_CH4221MEE01"
LOCATION"C767";
"2"
$PN"2"80;
"1"
$PN"1"51;
%"Q_CAP_DIFFBUS"
"2","(3625,850)","2","pure_quanta","I129";
;
LOCATION"C766"
$SEC"1"
CDS_SEC"1"
VALUE"DIFF BUS_0.22UF"
PIN_NAMES_ROTATE"TRUE"
CDS_LMAN_SYM_OUTLINE"-25,50,25,-50"
CDS_LIB"pure_quanta"
VOLTAGE"6.3V"
MATERIAL"X6S"
PACK_TYPE"C0201"
TOLERANCE"20%"
PART_NUMBER"SP_CH4221MEE01"
LOCATION"C766";
"2"
$PN"2"33;
"1"
$PN"1"48;
%"Q_CAP_DIFFBUS"
"2","(3625,1050)","2","pure_quanta","I130";
;
LOCATION"C764"
$SEC"1"
CDS_SEC"1"
VALUE"DIFF BUS_0.22UF"
PIN_NAMES_ROTATE"TRUE"
CDS_LIB"pure_quanta"
CDS_LMAN_SYM_OUTLINE"-25,50,25,-50"
VOLTAGE"6.3V"
MATERIAL"X6S"
PACK_TYPE"C0201"
TOLERANCE"20%"
PART_NUMBER"SP_CH4221MEE01"
LOCATION"C764";
"2"
$PN"2"73;
"1"
$PN"1"53;
%"Q_CAP_DIFFBUS"
"2","(3625,1000)","2","pure_quanta","I131";
;
LOCATION"C765"
$SEC"1"
CDS_SEC"1"
VALUE"DIFF BUS_0.22UF"
PIN_NAMES_ROTATE"TRUE"
CDS_LIB"pure_quanta"
CDS_LMAN_SYM_OUTLINE"-25,50,25,-50"
VOLTAGE"6.3V"
MATERIAL"X6S"
PACK_TYPE"C0201"
TOLERANCE"20%"
PART_NUMBER"SP_CH4221MEE01"
LOCATION"C765";
"2"
$PN"2"74;
"1"
$PN"1"49;
%"TAP"
"1","(2900,1250)","2","standard","I132";
;
CDS_LIB"standard"
BODY_TYPE"PLUMBING"
HDL_TAP"TRUE";
"B \NAC \NWC"16;
"S \NAC"
BN"5"30;
%"TAP"
"1","(2900,1450)","2","standard","I133";
;
CDS_LIB"standard"
BODY_TYPE"PLUMBING"
HDL_TAP"TRUE";
"B \NAC \NWC"16;
"S \NAC"
BN"6"71;
%"TAP"
"1","(2900,1650)","2","standard","I134";
;
CDS_LIB"standard"
BODY_TYPE"PLUMBING"
HDL_TAP"TRUE";
"B \NAC \NWC"16;
"S \NAC"
BN"7"17;
%"Q_CAP_DIFFBUS"
"2","(3625,1200)","2","pure_quanta","I135";
;
LOCATION"C763"
$SEC"1"
CDS_SEC"1"
VALUE"DIFF BUS_0.22UF"
PIN_NAMES_ROTATE"TRUE"
CDS_LIB"pure_quanta"
CDS_LMAN_SYM_OUTLINE"-25,50,25,-50"
VOLTAGE"6.3V"
MATERIAL"X6S"
PACK_TYPE"C0201"
TOLERANCE"20%"
PART_NUMBER"SP_CH4221MEE01"
LOCATION"C763";
"2"
$PN"2"38;
"1"
$PN"1"57;
%"Q_CAP_DIFFBUS"
"2","(3625,1250)","2","pure_quanta","I136";
;
LOCATION"C762"
$SEC"1"
CDS_SEC"1"
VALUE"DIFF BUS_0.22UF"
PIN_NAMES_ROTATE"TRUE"
CDS_LIB"pure_quanta"
CDS_LMAN_SYM_OUTLINE"-25,50,25,-50"
VOLTAGE"6.3V"
MATERIAL"X6S"
PACK_TYPE"C0201"
TOLERANCE"20%"
PART_NUMBER"SP_CH4221MEE01"
LOCATION"C762";
"2"
$PN"2"30;
"1"
$PN"1"54;
%"Q_CAP_DIFFBUS"
"2","(3625,1400)","2","pure_quanta","I137";
;
LOCATION"C761"
$SEC"1"
CDS_SEC"1"
VALUE"DIFF BUS_0.22UF"
PIN_NAMES_ROTATE"TRUE"
CDS_LIB"pure_quanta"
CDS_LMAN_SYM_OUTLINE"-25,50,25,-50"
VOLTAGE"6.3V"
MATERIAL"X6S"
PACK_TYPE"C0201"
TOLERANCE"20%"
PART_NUMBER"SP_CH4221MEE01"
LOCATION"C761";
"2"
$PN"2"18;
"1"
$PN"1"87;
%"Q_CAP_DIFFBUS"
"2","(3625,1450)","2","pure_quanta","I138";
;
LOCATION"C760"
$SEC"1"
CDS_SEC"1"
VALUE"DIFF BUS_0.22UF"
PIN_NAMES_ROTATE"TRUE"
CDS_LIB"pure_quanta"
CDS_LMAN_SYM_OUTLINE"-25,50,25,-50"
VOLTAGE"6.3V"
MATERIAL"X6S"
PACK_TYPE"C0201"
TOLERANCE"20%"
PART_NUMBER"SP_CH4221MEE01"
LOCATION"C760";
"2"
$PN"2"71;
"1"
$PN"1"55;
%"Q_CAP_DIFFBUS"
"2","(3625,1600)","2","pure_quanta","I139";
;
LOCATION"C759"
$SEC"1"
CDS_SEC"1"
VALUE"DIFF BUS_0.22UF"
PIN_NAMES_ROTATE"TRUE"
CDS_LIB"pure_quanta"
CDS_LMAN_SYM_OUTLINE"-25,50,25,-50"
VOLTAGE"6.3V"
MATERIAL"X6S"
PACK_TYPE"C0201"
TOLERANCE"20%"
PART_NUMBER"SP_CH4221MEE01"
LOCATION"C759";
"2"
$PN"2"86;
"1"
$PN"1"58;
%"Q_CAP_DIFFBUS"
"2","(3625,1650)","2","pure_quanta","I140";
;
LOCATION"C758"
$SEC"1"
CDS_SEC"1"
VALUE"DIFF BUS_0.22UF"
PIN_NAMES_ROTATE"TRUE"
CDS_LMAN_SYM_OUTLINE"-25,50,25,-50"
CDS_LIB"pure_quanta"
VOLTAGE"6.3V"
MATERIAL"X6S"
PACK_TYPE"C0201"
TOLERANCE"20%"
PART_NUMBER"SP_CH4221MEE01"
LOCATION"C758";
"2"
$PN"2"17;
"1"
$PN"1"56;
%"TAP"
"1","(2650,2175)","2","standard","I141";
;
CDS_LIB"standard"
BODY_TYPE"PLUMBING"
HDL_TAP"TRUE";
"B \NAC \NWC"9;
"S \NAC"
BN"8"46;
%"TAP"
"1","(2650,2375)","2","standard","I142";
;
CDS_LIB"standard"
BODY_TYPE"PLUMBING"
HDL_TAP"TRUE";
"B \NAC \NWC"9;
"S \NAC"
BN"9"77;
%"TAP"
"1","(2650,2575)","2","standard","I143";
;
CDS_LIB"standard"
BODY_TYPE"PLUMBING"
HDL_TAP"TRUE";
"B \NAC \NWC"9;
"S \NAC"
BN"10"72;
%"TAP"
"1","(2650,2775)","2","standard","I144";
;
CDS_LIB"standard"
BODY_TYPE"PLUMBING"
HDL_TAP"TRUE";
"B \NAC \NWC"9;
"S \NAC"
BN"11"85;
%"TAP"
"1","(2650,2975)","2","standard","I145";
;
CDS_LIB"standard"
BODY_TYPE"PLUMBING"
HDL_TAP"TRUE";
"B \NAC \NWC"9;
"S \NAC"
BN"12"81;
%"TAP"
"1","(2650,3175)","2","standard","I146";
;
CDS_LIB"standard"
BODY_TYPE"PLUMBING"
HDL_TAP"TRUE";
"B \NAC \NWC"9;
"S \NAC"
BN"13"20;
%"TAP"
"1","(2650,3375)","2","standard","I147";
;
CDS_LIB"standard"
BODY_TYPE"PLUMBING"
HDL_TAP"TRUE";
"B \NAC \NWC"9;
"S \NAC"
BN"14"89;
%"TAP"
"1","(2650,3575)","2","standard","I148";
;
CDS_LIB"standard"
BODY_TYPE"PLUMBING"
HDL_TAP"TRUE";
"B \NAC \NWC"9;
"S \NAC"
BN"15"47;
%"TAP"
"1","(2900,2225)","2","standard","I149";
;
CDS_LIB"standard"
BODY_TYPE"PLUMBING"
HDL_TAP"TRUE";
"B \NAC \NWC"13;
"S \NAC"
BN"8"45;
%"TAP"
"1","(2900,2425)","2","standard","I150";
;
CDS_LIB"standard"
BODY_TYPE"PLUMBING"
HDL_TAP"TRUE";
"B \NAC \NWC"13;
"S \NAC"
BN"9"43;
%"TAP"
"1","(2900,2625)","2","standard","I151";
;
CDS_LIB"standard"
BODY_TYPE"PLUMBING"
HDL_TAP"TRUE";
"B \NAC \NWC"13;
"S \NAC"
BN"10"42;
%"TAP"
"1","(2900,2825)","2","standard","I152";
;
CDS_LIB"standard"
BODY_TYPE"PLUMBING"
HDL_TAP"TRUE";
"B \NAC \NWC"13;
"S \NAC"
BN"11"44;
%"TAP"
"1","(2900,3025)","2","standard","I153";
;
CDS_LIB"standard"
BODY_TYPE"PLUMBING"
HDL_TAP"TRUE";
"B \NAC \NWC"13;
"S \NAC"
BN"12"84;
%"Q_CAP_DIFFBUS"
"2","(3625,2225)","2","pure_quanta","I154";
;
LOCATION"C756"
$SEC"1"
CDS_SEC"1"
VALUE"DIFF BUS_0.22UF"
CDS_LMAN_SYM_OUTLINE"-25,50,25,-50"
CDS_LIB"pure_quanta"
PIN_NAMES_ROTATE"TRUE"
VOLTAGE"6.3V"
MATERIAL"X6S"
PACK_TYPE"C0201"
TOLERANCE"20%"
PART_NUMBER"SP_CH4221MEE01"
LOCATION"C756";
"2"
$PN"2"45;
"1"
$PN"1"60;
%"Q_CAP_DIFFBUS"
"2","(3625,2175)","2","pure_quanta","I155";
;
LOCATION"C757"
$SEC"1"
CDS_SEC"1"
VALUE"DIFF BUS_0.22UF"
CDS_LMAN_SYM_OUTLINE"-25,50,25,-50"
CDS_LIB"pure_quanta"
PIN_NAMES_ROTATE"TRUE"
VOLTAGE"6.3V"
MATERIAL"X6S"
PACK_TYPE"C0201"
TOLERANCE"20%"
PART_NUMBER"SP_CH4221MEE01"
LOCATION"C757";
"2"
$PN"2"46;
"1"
$PN"1"63;
%"Q_CAP_DIFFBUS"
"2","(3625,2375)","2","pure_quanta","I156";
;
LOCATION"C755"
$SEC"1"
CDS_SEC"1"
VALUE"DIFF BUS_0.22UF"
CDS_LMAN_SYM_OUTLINE"-25,50,25,-50"
CDS_LIB"pure_quanta"
PIN_NAMES_ROTATE"TRUE"
VOLTAGE"6.3V"
MATERIAL"X6S"
PACK_TYPE"C0201"
TOLERANCE"20%"
PART_NUMBER"SP_CH4221MEE01"
LOCATION"C755";
"2"
$PN"2"77;
"1"
$PN"1"78;
%"Q_CAP_DIFFBUS"
"2","(3625,2425)","2","pure_quanta","I157";
;
LOCATION"C754"
$SEC"1"
CDS_SEC"1"
VALUE"DIFF BUS_0.22UF"
CDS_LIB"pure_quanta"
CDS_LMAN_SYM_OUTLINE"-25,50,25,-50"
PIN_NAMES_ROTATE"TRUE"
VOLTAGE"6.3V"
MATERIAL"X6S"
PACK_TYPE"C0201"
TOLERANCE"20%"
PART_NUMBER"SP_CH4221MEE01"
LOCATION"C754";
"2"
$PN"2"43;
"1"
$PN"1"59;
%"Q_CAP_DIFFBUS"
"2","(3625,2575)","2","pure_quanta","I158";
;
LOCATION"C753"
$SEC"1"
CDS_SEC"1"
VALUE"DIFF BUS_0.22UF"
CDS_LMAN_SYM_OUTLINE"-25,50,25,-50"
CDS_LIB"pure_quanta"
PIN_NAMES_ROTATE"TRUE"
VOLTAGE"6.3V"
MATERIAL"X6S"
PACK_TYPE"C0201"
TOLERANCE"20%"
PART_NUMBER"SP_CH4221MEE01"
LOCATION"C753";
"2"
$PN"2"72;
"1"
$PN"1"76;
%"Q_CAP_DIFFBUS"
"2","(3625,2625)","2","pure_quanta","I159";
;
LOCATION"C752"
$SEC"1"
CDS_SEC"1"
VALUE"DIFF BUS_0.22UF"
CDS_LMAN_SYM_OUTLINE"-25,50,25,-50"
CDS_LIB"pure_quanta"
PIN_NAMES_ROTATE"TRUE"
VOLTAGE"6.3V"
MATERIAL"X6S"
PACK_TYPE"C0201"
TOLERANCE"20%"
PART_NUMBER"SP_CH4221MEE01"
LOCATION"C752";
"2"
$PN"2"42;
"1"
$PN"1"61;
%"Q_CAP_DIFFBUS"
"2","(3625,2825)","2","pure_quanta","I160";
;
LOCATION"C750"
$SEC"1"
CDS_SEC"1"
VALUE"DIFF BUS_0.22UF"
CDS_LIB"pure_quanta"
CDS_LMAN_SYM_OUTLINE"-25,50,25,-50"
PIN_NAMES_ROTATE"TRUE"
VOLTAGE"6.3V"
MATERIAL"X6S"
PACK_TYPE"C0201"
TOLERANCE"20%"
PART_NUMBER"SP_CH4221MEE01"
LOCATION"C750";
"2"
$PN"2"44;
"1"
$PN"1"62;
%"Q_CAP_DIFFBUS"
"2","(3625,2775)","2","pure_quanta","I161";
;
LOCATION"C751"
$SEC"1"
CDS_SEC"1"
VALUE"DIFF BUS_0.22UF"
CDS_LIB"pure_quanta"
CDS_LMAN_SYM_OUTLINE"-25,50,25,-50"
PIN_NAMES_ROTATE"TRUE"
VOLTAGE"6.3V"
MATERIAL"X6S"
PACK_TYPE"C0201"
TOLERANCE"20%"
PART_NUMBER"SP_CH4221MEE01"
LOCATION"C751";
"2"
$PN"2"85;
"1"
$PN"1"70;
%"Q_CAP_DIFFBUS"
"2","(3625,2975)","2","pure_quanta","I162";
;
LOCATION"C749"
$SEC"1"
CDS_SEC"1"
VALUE"DIFF BUS_0.22UF"
CDS_LMAN_SYM_OUTLINE"-25,50,25,-50"
CDS_LIB"pure_quanta"
PIN_NAMES_ROTATE"TRUE"
VOLTAGE"6.3V"
MATERIAL"X6S"
PACK_TYPE"C0201"
TOLERANCE"20%"
PART_NUMBER"SP_CH4221MEE01"
LOCATION"C749";
"2"
$PN"2"81;
"1"
$PN"1"82;
%"Q_CAP_DIFFBUS"
"2","(3625,3025)","2","pure_quanta","I163";
;
LOCATION"C748"
$SEC"1"
CDS_SEC"1"
VALUE"DIFF BUS_0.22UF"
CDS_LMAN_SYM_OUTLINE"-25,50,25,-50"
CDS_LIB"pure_quanta"
PIN_NAMES_ROTATE"TRUE"
VOLTAGE"6.3V"
MATERIAL"X6S"
PACK_TYPE"C0201"
TOLERANCE"20%"
PART_NUMBER"SP_CH4221MEE01"
LOCATION"C748";
"2"
$PN"2"84;
"1"
$PN"1"83;
%"TAP"
"1","(2900,3225)","2","standard","I164";
;
CDS_LIB"standard"
BODY_TYPE"PLUMBING"
HDL_TAP"TRUE";
"B \NAC \NWC"13;
"S \NAC"
BN"13"40;
%"TAP"
"1","(2900,3425)","2","standard","I165";
;
CDS_LIB"standard"
BODY_TYPE"PLUMBING"
HDL_TAP"TRUE";
"B \NAC \NWC"13;
"S \NAC"
BN"14"41;
%"TAP"
"1","(2900,3625)","2","standard","I166";
;
CDS_LIB"standard"
BODY_TYPE"PLUMBING"
HDL_TAP"TRUE";
"B \NAC \NWC"13;
"S \NAC"
BN"15"39;
%"Q_CAP_DIFFBUS"
"2","(3625,3175)","2","pure_quanta","I167";
;
LOCATION"C747"
$SEC"1"
CDS_SEC"1"
VALUE"DIFF BUS_0.22UF"
CDS_LMAN_SYM_OUTLINE"-25,50,25,-50"
CDS_LIB"pure_quanta"
PIN_NAMES_ROTATE"TRUE"
VOLTAGE"6.3V"
MATERIAL"X6S"
PACK_TYPE"C0201"
TOLERANCE"20%"
PART_NUMBER"SP_CH4221MEE01"
LOCATION"C747";
"2"
$PN"2"20;
"1"
$PN"1"67;
%"Q_CAP_DIFFBUS"
"2","(3625,3225)","2","pure_quanta","I168";
;
LOCATION"C746"
$SEC"1"
CDS_SEC"1"
VALUE"DIFF BUS_0.22UF"
CDS_LMAN_SYM_OUTLINE"-25,50,25,-50"
CDS_LIB"pure_quanta"
PIN_NAMES_ROTATE"TRUE"
VOLTAGE"6.3V"
MATERIAL"X6S"
PACK_TYPE"C0201"
TOLERANCE"20%"
PART_NUMBER"SP_CH4221MEE01"
LOCATION"C746";
"2"
$PN"2"40;
"1"
$PN"1"88;
%"Q_CAP_DIFFBUS"
"2","(3625,3375)","2","pure_quanta","I169";
;
LOCATION"C745"
$SEC"1"
CDS_SEC"1"
VALUE"DIFF BUS_0.22UF"
CDS_LMAN_SYM_OUTLINE"-25,50,25,-50"
CDS_LIB"pure_quanta"
PIN_NAMES_ROTATE"TRUE"
VOLTAGE"6.3V"
MATERIAL"X6S"
PACK_TYPE"C0201"
TOLERANCE"20%"
PART_NUMBER"SP_CH4221MEE01"
LOCATION"C745";
"2"
$PN"2"89;
"1"
$PN"1"66;
%"Q_CAP_DIFFBUS"
"2","(3625,3425)","2","pure_quanta","I170";
;
LOCATION"C744"
$SEC"1"
CDS_SEC"1"
VALUE"DIFF BUS_0.22UF"
CDS_LMAN_SYM_OUTLINE"-25,50,25,-50"
CDS_LIB"pure_quanta"
PIN_NAMES_ROTATE"TRUE"
VOLTAGE"6.3V"
MATERIAL"X6S"
PACK_TYPE"C0201"
TOLERANCE"20%"
PART_NUMBER"SP_CH4221MEE01"
LOCATION"C744";
"2"
$PN"2"41;
"1"
$PN"1"64;
%"Q_CAP_DIFFBUS"
"2","(3625,3575)","2","pure_quanta","I171";
;
LOCATION"C743"
$SEC"1"
CDS_SEC"1"
VALUE"DIFF BUS_0.22UF"
CDS_LMAN_SYM_OUTLINE"-25,50,25,-50"
CDS_LIB"pure_quanta"
PIN_NAMES_ROTATE"TRUE"
VOLTAGE"6.3V"
MATERIAL"X6S"
PACK_TYPE"C0201"
TOLERANCE"20%"
PART_NUMBER"SP_CH4221MEE01"
LOCATION"C743";
"2"
$PN"2"47;
"1"
$PN"1"65;
%"Q_CAP_DIFFBUS"
"2","(3625,3625)","2","pure_quanta","I172";
;
LOCATION"C742"
$SEC"1"
CDS_SEC"1"
VOLTAGE"6.3V"
TOLERANCE"20%"
MATERIAL"X6S"
PACK_TYPE"C0201"
VALUE"DIFF BUS_0.22UF"
CDS_LIB"pure_quanta"
CDS_LMAN_SYM_OUTLINE"-25,50,25,-50"
PIN_NAMES_ROTATE"TRUE"
PART_NUMBER"SP_CH4221MEE01"
LOCATION"C742";
"2"
$PN"2"39;
"1"
$PN"1"19;
%"TAP"
"1","(4175,250)","0","standard","I173";
;
CDS_LIB"standard"
BODY_TYPE"PLUMBING"
HDL_TAP"TRUE";
"B \NAC \NWC"15;
"S \NAC"
BN"0"69;
%"TAP"
"1","(4175,450)","0","standard","I174";
;
CDS_LIB"standard"
BODY_TYPE"PLUMBING"
HDL_TAP"TRUE";
"B \NAC \NWC"15;
"S \NAC"
BN"1"75;
%"TAP"
"1","(4175,650)","0","standard","I175";
;
CDS_LIB"standard"
BODY_TYPE"PLUMBING"
HDL_TAP"TRUE";
"B \NAC \NWC"15;
"S \NAC"
BN"2"79;
%"TAP"
"1","(4175,1050)","0","standard","I176";
;
CDS_LIB"standard"
BODY_TYPE"PLUMBING"
HDL_TAP"TRUE";
"B \NAC \NWC"15;
"S \NAC"
BN"4"53;
%"TAP"
"1","(4175,850)","0","standard","I177";
;
CDS_LIB"standard"
BODY_TYPE"PLUMBING"
HDL_TAP"TRUE";
"B \NAC \NWC"15;
"S \NAC"
BN"3"48;
%"TAP"
"1","(4375,200)","0","standard","I178";
;
CDS_LIB"standard"
BODY_TYPE"PLUMBING"
HDL_TAP"TRUE";
"B \NAC \NWC"11;
"S \NAC"
BN"0"52;
%"TAP"
"1","(4375,400)","0","standard","I179";
;
CDS_LIB"standard"
BODY_TYPE"PLUMBING"
HDL_TAP"TRUE";
"B \NAC \NWC"11;
"S \NAC"
BN"1"68;
%"TAP"
"1","(4375,600)","0","standard","I180";
;
CDS_LIB"standard"
BODY_TYPE"PLUMBING"
HDL_TAP"TRUE";
"B \NAC \NWC"11;
"S \NAC"
BN"2"50;
%"TAP"
"1","(4375,800)","0","standard","I181";
;
CDS_LIB"standard"
BODY_TYPE"PLUMBING"
HDL_TAP"TRUE";
"B \NAC \NWC"11;
"S \NAC"
BN"3"51;
%"TAP"
"1","(4375,1000)","0","standard","I182";
;
CDS_LIB"standard"
BODY_TYPE"PLUMBING"
HDL_TAP"TRUE";
"B \NAC \NWC"11;
"S \NAC"
BN"4"49;
%"TAP"
"1","(4175,1250)","0","standard","I183";
;
CDS_LIB"standard"
BODY_TYPE"PLUMBING"
HDL_TAP"TRUE";
"B \NAC \NWC"15;
"S \NAC"
BN"5"54;
%"TAP"
"1","(4175,1450)","0","standard","I184";
;
CDS_LIB"standard"
BODY_TYPE"PLUMBING"
HDL_TAP"TRUE";
"B \NAC \NWC"15;
"S \NAC"
BN"6"55;
%"TAP"
"1","(4175,1650)","0","standard","I185";
;
CDS_LIB"standard"
BODY_TYPE"PLUMBING"
HDL_TAP"TRUE";
"B \NAC \NWC"15;
"S \NAC"
BN"7"56;
%"TAP"
"1","(4375,1200)","0","standard","I186";
;
CDS_LIB"standard"
BODY_TYPE"PLUMBING"
HDL_TAP"TRUE";
"B \NAC \NWC"11;
"S \NAC"
BN"5"57;
%"TAP"
"1","(4375,1400)","0","standard","I187";
;
CDS_LIB"standard"
BODY_TYPE"PLUMBING"
HDL_TAP"TRUE";
"B \NAC \NWC"11;
"S \NAC"
BN"6"87;
%"TAP"
"1","(4375,1600)","0","standard","I188";
;
CDS_LIB"standard"
BODY_TYPE"PLUMBING"
HDL_TAP"TRUE";
"B \NAC \NWC"11;
"S \NAC"
BN"7"58;
%"TAP"
"1","(4175,2225)","0","standard","I191";
;
CDS_LIB"standard"
BODY_TYPE"PLUMBING"
HDL_TAP"TRUE";
"B \NAC \NWC"10;
"S \NAC"
BN"8"60;
%"TAP"
"1","(4175,2425)","0","standard","I192";
;
CDS_LIB"standard"
BODY_TYPE"PLUMBING"
HDL_TAP"TRUE";
"B \NAC \NWC"10;
"S \NAC"
BN"9"59;
%"TAP"
"1","(4175,2625)","0","standard","I193";
;
CDS_LIB"standard"
BODY_TYPE"PLUMBING"
HDL_TAP"TRUE";
"B \NAC \NWC"10;
"S \NAC"
BN"10"61;
%"TAP"
"1","(4175,2825)","0","standard","I194";
;
CDS_LIB"standard"
BODY_TYPE"PLUMBING"
HDL_TAP"TRUE";
"B \NAC \NWC"10;
"S \NAC"
BN"11"62;
%"TAP"
"1","(4175,3025)","0","standard","I195";
;
CDS_LIB"standard"
BODY_TYPE"PLUMBING"
HDL_TAP"TRUE";
"B \NAC \NWC"10;
"S \NAC"
BN"12"83;
%"TAP"
"1","(4375,2175)","0","standard","I196";
;
CDS_LIB"standard"
BODY_TYPE"PLUMBING"
HDL_TAP"TRUE";
"B \NAC \NWC"14;
"S \NAC"
BN"8"63;
%"TAP"
"1","(4375,2375)","0","standard","I197";
;
CDS_LIB"standard"
BODY_TYPE"PLUMBING"
HDL_TAP"TRUE";
"B \NAC \NWC"14;
"S \NAC"
BN"9"78;
%"TAP"
"1","(4375,2575)","0","standard","I198";
;
CDS_LIB"standard"
BODY_TYPE"PLUMBING"
HDL_TAP"TRUE";
"B \NAC \NWC"14;
"S \NAC"
BN"10"76;
%"TAP"
"1","(4375,2775)","0","standard","I199";
;
CDS_LIB"standard"
BODY_TYPE"PLUMBING"
HDL_TAP"TRUE";
"B \NAC \NWC"14;
"S \NAC"
BN"11"70;
%"TAP"
"1","(4375,2975)","0","standard","I200";
;
CDS_LIB"standard"
BODY_TYPE"PLUMBING"
HDL_TAP"TRUE";
"B \NAC \NWC"14;
"S \NAC"
BN"12"82;
%"TAP"
"1","(4175,3225)","0","standard","I201";
;
CDS_LIB"standard"
BODY_TYPE"PLUMBING"
HDL_TAP"TRUE";
"B \NAC \NWC"10;
"S \NAC"
BN"13"88;
%"TAP"
"1","(4175,3625)","0","standard","I202";
;
CDS_LIB"standard"
BODY_TYPE"PLUMBING"
HDL_TAP"TRUE";
"B \NAC \NWC"10;
"S \NAC"
BN"15"19;
%"TAP"
"1","(4175,3425)","0","standard","I203";
;
CDS_LIB"standard"
BODY_TYPE"PLUMBING"
HDL_TAP"TRUE";
"B \NAC \NWC"10;
"S \NAC"
BN"14"64;
%"TAP"
"1","(4375,3175)","0","standard","I204";
;
CDS_LIB"standard"
BODY_TYPE"PLUMBING"
HDL_TAP"TRUE";
"B \NAC \NWC"14;
"S \NAC"
BN"13"67;
%"TAP"
"1","(4375,3375)","0","standard","I205";
;
CDS_LIB"standard"
BODY_TYPE"PLUMBING"
HDL_TAP"TRUE";
"B \NAC \NWC"14;
"S \NAC"
BN"14"66;
%"TAP"
"1","(4375,3575)","0","standard","I206";
;
CDS_LIB"standard"
BODY_TYPE"PLUMBING"
HDL_TAP"TRUE";
"B \NAC \NWC"14;
"S \NAC"
BN"15"65;
%"TAP"
"1","(-1925,175)","2","standard","I213";
;
CDS_LIB"standard"
BODY_TYPE"PLUMBING"
HDL_TAP"TRUE";
"B \NAC \NWC"3;
"S \NAC"
BN"0"91;
%"TAP"
"1","(-1925,375)","2","standard","I214";
;
CDS_LIB"standard"
BODY_TYPE"PLUMBING"
HDL_TAP"TRUE";
"B \NAC \NWC"3;
"S \NAC"
BN"1"26;
%"TAP"
"1","(-1675,225)","2","standard","I215";
;
CDS_LIB"standard"
BODY_TYPE"PLUMBING"
HDL_TAP"TRUE";
"B \NAC \NWC"8;
"S \NAC"
BN"0"27;
%"TAP"
"1","(-1675,425)","2","standard","I216";
;
CDS_LIB"standard"
BODY_TYPE"PLUMBING"
HDL_TAP"TRUE";
"B \NAC \NWC"8;
"S \NAC"
BN"1"95;
%"TAP"
"1","(-1925,575)","2","standard","I217";
;
CDS_LIB"standard"
BODY_TYPE"PLUMBING"
HDL_TAP"TRUE";
"B \NAC \NWC"3;
"S \NAC"
BN"2"94;
%"TAP"
"1","(-1925,775)","2","standard","I218";
;
CDS_LIB"standard"
BODY_TYPE"PLUMBING"
HDL_TAP"TRUE";
"B \NAC \NWC"3;
"S \NAC"
BN"3"93;
%"TAP"
"1","(-1925,975)","2","standard","I219";
;
CDS_LIB"standard"
BODY_TYPE"PLUMBING"
HDL_TAP"TRUE";
"B \NAC \NWC"3;
"S \NAC"
BN"4"92;
%"TAP"
"1","(-1675,625)","2","standard","I220";
;
CDS_LIB"standard"
BODY_TYPE"PLUMBING"
HDL_TAP"TRUE";
"B \NAC \NWC"8;
"S \NAC"
BN"2"90;
%"TAP"
"1","(-1675,825)","2","standard","I221";
;
CDS_LIB"standard"
BODY_TYPE"PLUMBING"
HDL_TAP"TRUE";
"B \NAC \NWC"8;
"S \NAC"
BN"3"100;
%"TAP"
"1","(-1925,1175)","2","standard","I222";
;
CDS_LIB"standard"
BODY_TYPE"PLUMBING"
HDL_TAP"TRUE";
"B \NAC \NWC"3;
"S \NAC"
BN"5"98;
%"TAP"
"1","(-1925,1375)","2","standard","I223";
;
CDS_LIB"standard"
BODY_TYPE"PLUMBING"
HDL_TAP"TRUE";
"B \NAC \NWC"3;
"S \NAC"
BN"6"99;
%"TAP"
"1","(-1675,1225)","2","standard","I224";
;
CDS_LIB"standard"
BODY_TYPE"PLUMBING"
HDL_TAP"TRUE";
"B \NAC \NWC"8;
"S \NAC"
BN"5"97;
%"TAP"
"1","(-1675,1025)","2","standard","I225";
;
CDS_LIB"standard"
BODY_TYPE"PLUMBING"
HDL_TAP"TRUE";
"B \NAC \NWC"8;
"S \NAC"
BN"4"25;
%"TAP"
"1","(-1675,1425)","2","standard","I226";
;
CDS_LIB"standard"
BODY_TYPE"PLUMBING"
HDL_TAP"TRUE";
"B \NAC \NWC"8;
"S \NAC"
BN"6"101;
%"TAP"
"1","(-1925,1575)","2","standard","I227";
;
CDS_LIB"standard"
BODY_TYPE"PLUMBING"
HDL_TAP"TRUE";
"B \NAC \NWC"3;
"S \NAC"
BN"7"136;
%"TAP"
"1","(-1675,1625)","2","standard","I228";
;
CDS_LIB"standard"
BODY_TYPE"PLUMBING"
HDL_TAP"TRUE";
"B \NAC \NWC"8;
"S \NAC"
BN"7"96;
%"Q_CAP_DIFFBUS"
"2","(-950,225)","2","pure_quanta","I229";
;
LOCATION"C740"
$SEC"1"
CDS_SEC"1"
VALUE"DIFF BUS_0.22UF"
PIN_NAMES_ROTATE"TRUE"
CDS_LIB"pure_quanta"
CDS_LMAN_SYM_OUTLINE"-25,50,25,-50"
VOLTAGE"6.3V"
MATERIAL"X6S"
PACK_TYPE"C0201"
TOLERANCE"20%"
PART_NUMBER"SP_CH4221MEE01"
LOCATION"C740";
"2"
$PN"2"27;
"1"
$PN"1"105;
%"Q_CAP_DIFFBUS"
"2","(-950,175)","2","pure_quanta","I230";
;
LOCATION"C741"
$SEC"1"
CDS_SEC"1"
VALUE"DIFF BUS_0.22UF"
PIN_NAMES_ROTATE"TRUE"
CDS_LIB"pure_quanta"
CDS_LMAN_SYM_OUTLINE"-25,50,25,-50"
VOLTAGE"6.3V"
MATERIAL"X6S"
PACK_TYPE"C0201"
TOLERANCE"20%"
PART_NUMBER"SP_CH4221MEE01"
LOCATION"C741";
"2"
$PN"2"91;
"1"
$PN"1"102;
%"Q_CAP_DIFFBUS"
"2","(-950,375)","2","pure_quanta","I231";
;
LOCATION"C739"
$SEC"1"
CDS_SEC"1"
VALUE"DIFF BUS_0.22UF"
PIN_NAMES_ROTATE"TRUE"
CDS_LIB"pure_quanta"
CDS_LMAN_SYM_OUTLINE"-25,50,25,-50"
VOLTAGE"6.3V"
MATERIAL"X6S"
PACK_TYPE"C0201"
TOLERANCE"20%"
PART_NUMBER"SP_CH4221MEE01"
LOCATION"C739";
"2"
$PN"2"26;
"1"
$PN"1"107;
%"Q_CAP_DIFFBUS"
"2","(-950,425)","2","pure_quanta","I232";
;
LOCATION"C738"
$SEC"1"
CDS_SEC"1"
VALUE"DIFF BUS_0.22UF"
PIN_NAMES_ROTATE"TRUE"
CDS_LMAN_SYM_OUTLINE"-25,50,25,-50"
CDS_LIB"pure_quanta"
VOLTAGE"6.3V"
MATERIAL"X6S"
PACK_TYPE"C0201"
TOLERANCE"20%"
PART_NUMBER"SP_CH4221MEE01"
LOCATION"C738";
"2"
$PN"2"95;
"1"
$PN"1"104;
%"Q_CAP_DIFFBUS"
"2","(-950,575)","2","pure_quanta","I233";
;
LOCATION"C737"
$SEC"1"
CDS_SEC"1"
VALUE"DIFF BUS_0.22UF"
PIN_NAMES_ROTATE"TRUE"
CDS_LIB"pure_quanta"
CDS_LMAN_SYM_OUTLINE"-25,50,25,-50"
VOLTAGE"6.3V"
MATERIAL"X6S"
PACK_TYPE"C0201"
TOLERANCE"20%"
PART_NUMBER"SP_CH4221MEE01"
LOCATION"C737";
"2"
$PN"2"94;
"1"
$PN"1"28;
%"Q_CAP_DIFFBUS"
"2","(-950,625)","2","pure_quanta","I234";
;
LOCATION"C736"
$SEC"1"
CDS_SEC"1"
VALUE"DIFF BUS_0.22UF"
PIN_NAMES_ROTATE"TRUE"
CDS_LIB"pure_quanta"
CDS_LMAN_SYM_OUTLINE"-25,50,25,-50"
VOLTAGE"6.3V"
MATERIAL"X6S"
PACK_TYPE"C0201"
TOLERANCE"20%"
PART_NUMBER"SP_CH4221MEE01"
LOCATION"C736";
"2"
$PN"2"90;
"1"
$PN"1"103;
%"Q_CAP_DIFFBUS"
"2","(-950,825)","2","pure_quanta","I235";
;
LOCATION"C734"
$SEC"1"
CDS_SEC"1"
VALUE"DIFF BUS_0.22UF"
PIN_NAMES_ROTATE"TRUE"
CDS_LMAN_SYM_OUTLINE"-25,50,25,-50"
CDS_LIB"pure_quanta"
VOLTAGE"6.3V"
MATERIAL"X6S"
PACK_TYPE"C0201"
TOLERANCE"20%"
PART_NUMBER"SP_CH4221MEE01"
LOCATION"C734";
"2"
$PN"2"100;
"1"
$PN"1"106;
%"Q_CAP_DIFFBUS"
"2","(-950,775)","2","pure_quanta","I236";
;
LOCATION"C735"
$SEC"1"
CDS_SEC"1"
VALUE"DIFF BUS_0.22UF"
PIN_NAMES_ROTATE"TRUE"
CDS_LMAN_SYM_OUTLINE"-25,50,25,-50"
CDS_LIB"pure_quanta"
VOLTAGE"6.3V"
MATERIAL"X6S"
PACK_TYPE"C0201"
TOLERANCE"20%"
PART_NUMBER"SP_CH4221MEE01"
LOCATION"C735";
"2"
$PN"2"93;
"1"
$PN"1"108;
%"Q_CAP_DIFFBUS"
"2","(-950,975)","2","pure_quanta","I237";
;
LOCATION"C733"
$SEC"1"
CDS_SEC"1"
VALUE"DIFF BUS_0.22UF"
PIN_NAMES_ROTATE"TRUE"
CDS_LIB"pure_quanta"
CDS_LMAN_SYM_OUTLINE"-25,50,25,-50"
VOLTAGE"6.3V"
MATERIAL"X6S"
PACK_TYPE"C0201"
TOLERANCE"20%"
PART_NUMBER"SP_CH4221MEE01"
LOCATION"C733";
"2"
$PN"2"92;
"1"
$PN"1"132;
%"TAP"
"1","(-400,225)","0","standard","I238";
;
CDS_LIB"standard"
BODY_TYPE"PLUMBING"
HDL_TAP"TRUE";
"B \NAC \NWC"4;
"S \NAC"
BN"0"105;
%"TAP"
"1","(-400,425)","0","standard","I239";
;
CDS_LIB"standard"
BODY_TYPE"PLUMBING"
HDL_TAP"TRUE";
"B \NAC \NWC"4;
"S \NAC"
BN"1"104;
%"TAP"
"1","(-200,175)","0","standard","I240";
;
CDS_LIB"standard"
BODY_TYPE"PLUMBING"
HDL_TAP"TRUE";
"B \NAC \NWC"5;
"S \NAC"
BN"0"102;
%"TAP"
"1","(-200,375)","0","standard","I241";
;
CDS_LIB"standard"
BODY_TYPE"PLUMBING"
HDL_TAP"TRUE";
"B \NAC \NWC"5;
"S \NAC"
BN"1"107;
%"TAP"
"1","(-400,625)","0","standard","I242";
;
CDS_LIB"standard"
BODY_TYPE"PLUMBING"
HDL_TAP"TRUE";
"B \NAC \NWC"4;
"S \NAC"
BN"2"103;
%"TAP"
"1","(-400,825)","0","standard","I243";
;
CDS_LIB"standard"
BODY_TYPE"PLUMBING"
HDL_TAP"TRUE";
"B \NAC \NWC"4;
"S \NAC"
BN"3"106;
%"TAP"
"1","(-200,575)","0","standard","I244";
;
CDS_LIB"standard"
BODY_TYPE"PLUMBING"
HDL_TAP"TRUE";
"B \NAC \NWC"5;
"S \NAC"
BN"2"28;
%"TAP"
"1","(-200,775)","0","standard","I245";
;
CDS_LIB"standard"
BODY_TYPE"PLUMBING"
HDL_TAP"TRUE";
"B \NAC \NWC"5;
"S \NAC"
BN"3"108;
%"Q_CAP_DIFFBUS"
"2","(-950,1025)","2","pure_quanta","I246";
;
LOCATION"C732"
$SEC"1"
CDS_SEC"1"
VALUE"DIFF BUS_0.22UF"
PIN_NAMES_ROTATE"TRUE"
CDS_LIB"pure_quanta"
CDS_LMAN_SYM_OUTLINE"-25,50,25,-50"
VOLTAGE"6.3V"
MATERIAL"X6S"
PACK_TYPE"C0201"
TOLERANCE"20%"
PART_NUMBER"SP_CH4221MEE01"
LOCATION"C732";
"2"
$PN"2"25;
"1"
$PN"1"109;
%"Q_CAP_DIFFBUS"
"2","(-950,1175)","2","pure_quanta","I247";
;
LOCATION"C731"
$SEC"1"
CDS_SEC"1"
VALUE"DIFF BUS_0.22UF"
PIN_NAMES_ROTATE"TRUE"
CDS_LIB"pure_quanta"
CDS_LMAN_SYM_OUTLINE"-25,50,25,-50"
VOLTAGE"6.3V"
MATERIAL"X6S"
PACK_TYPE"C0201"
TOLERANCE"20%"
PART_NUMBER"SP_CH4221MEE01"
LOCATION"C731";
"2"
$PN"2"98;
"1"
$PN"1"133;
%"Q_CAP_DIFFBUS"
"2","(-950,1225)","2","pure_quanta","I248";
;
LOCATION"C730"
$SEC"1"
CDS_SEC"1"
VALUE"DIFF BUS_0.22UF"
PIN_NAMES_ROTATE"TRUE"
CDS_LIB"pure_quanta"
CDS_LMAN_SYM_OUTLINE"-25,50,25,-50"
VOLTAGE"6.3V"
MATERIAL"X6S"
PACK_TYPE"C0201"
TOLERANCE"20%"
PART_NUMBER"SP_CH4221MEE01"
LOCATION"C730";
"2"
$PN"2"97;
"1"
$PN"1"111;
%"Q_CAP_DIFFBUS"
"2","(-950,1375)","2","pure_quanta","I249";
;
LOCATION"C729"
$SEC"1"
CDS_SEC"1"
VALUE"DIFF BUS_0.22UF"
PIN_NAMES_ROTATE"TRUE"
CDS_LIB"pure_quanta"
CDS_LMAN_SYM_OUTLINE"-25,50,25,-50"
VOLTAGE"6.3V"
MATERIAL"X6S"
PACK_TYPE"C0201"
TOLERANCE"20%"
PART_NUMBER"SP_CH4221MEE01"
LOCATION"C729";
"2"
$PN"2"99;
"1"
$PN"1"134;
%"Q_CAP_DIFFBUS"
"2","(-950,1425)","2","pure_quanta","I250";
;
LOCATION"C728"
$SEC"1"
CDS_SEC"1"
VALUE"DIFF BUS_0.22UF"
PIN_NAMES_ROTATE"TRUE"
CDS_LIB"pure_quanta"
CDS_LMAN_SYM_OUTLINE"-25,50,25,-50"
VOLTAGE"6.3V"
MATERIAL"X6S"
PACK_TYPE"C0201"
TOLERANCE"20%"
PART_NUMBER"SP_CH4221MEE01"
LOCATION"C728";
"2"
$PN"2"101;
"1"
$PN"1"135;
%"Q_CAP_DIFFBUS"
"2","(-950,1575)","2","pure_quanta","I251";
;
LOCATION"C727"
$SEC"1"
CDS_SEC"1"
VALUE"DIFF BUS_0.22UF"
PIN_NAMES_ROTATE"TRUE"
CDS_LIB"pure_quanta"
CDS_LMAN_SYM_OUTLINE"-25,50,25,-50"
VOLTAGE"6.3V"
MATERIAL"X6S"
PACK_TYPE"C0201"
TOLERANCE"20%"
PART_NUMBER"SP_CH4221MEE01"
LOCATION"C727";
"2"
$PN"2"136;
"1"
$PN"1"24;
%"TAP"
"1","(-400,1025)","0","standard","I252";
;
CDS_LIB"standard"
BODY_TYPE"PLUMBING"
HDL_TAP"TRUE";
"B \NAC \NWC"4;
"S \NAC"
BN"4"109;
%"TAP"
"1","(-400,1425)","0","standard","I253";
;
CDS_LIB"standard"
BODY_TYPE"PLUMBING"
HDL_TAP"TRUE";
"B \NAC \NWC"4;
"S \NAC"
BN"6"135;
%"TAP"
"1","(-200,1175)","0","standard","I254";
;
CDS_LIB"standard"
BODY_TYPE"PLUMBING"
HDL_TAP"TRUE";
"B \NAC \NWC"5;
"S \NAC"
BN"5"133;
%"TAP"
"1","(-200,1375)","0","standard","I255";
;
CDS_LIB"standard"
BODY_TYPE"PLUMBING"
HDL_TAP"TRUE";
"B \NAC \NWC"5;
"S \NAC"
BN"6"134;
%"TAP"
"1","(-400,1625)","0","standard","I256";
;
CDS_LIB"standard"
BODY_TYPE"PLUMBING"
HDL_TAP"TRUE";
"B \NAC \NWC"4;
"S \NAC"
BN"7"110;
%"TAP"
"1","(-200,1575)","0","standard","I257";
;
CDS_LIB"standard"
BODY_TYPE"PLUMBING"
HDL_TAP"TRUE";
"B \NAC \NWC"5;
"S \NAC"
BN"7"24;
%"TAP"
"1","(-1925,2150)","2","standard","I258";
;
CDS_LIB"standard"
BODY_TYPE"PLUMBING"
HDL_TAP"TRUE";
"B \NAC \NWC"1;
"S \NAC"
BN"8"29;
%"TAP"
"1","(-1925,2350)","2","standard","I259";
;
CDS_LIB"standard"
BODY_TYPE"PLUMBING"
HDL_TAP"TRUE";
"B \NAC \NWC"1;
"S \NAC"
BN"9"114;
%"TAP"
"1","(-1675,2200)","2","standard","I260";
;
CDS_LIB"standard"
BODY_TYPE"PLUMBING"
HDL_TAP"TRUE";
"B \NAC \NWC"2;
"S \NAC"
BN"8"116;
%"TAP"
"1","(-1675,2400)","2","standard","I261";
;
CDS_LIB"standard"
BODY_TYPE"PLUMBING"
HDL_TAP"TRUE";
"B \NAC \NWC"2;
"S \NAC"
BN"9"137;
%"TAP"
"1","(-1925,2750)","2","standard","I262";
;
CDS_LIB"standard"
BODY_TYPE"PLUMBING"
HDL_TAP"TRUE";
"B \NAC \NWC"1;
"S \NAC"
BN"11"138;
%"TAP"
"1","(-1925,2550)","2","standard","I263";
;
CDS_LIB"standard"
BODY_TYPE"PLUMBING"
HDL_TAP"TRUE";
"B \NAC \NWC"1;
"S \NAC"
BN"10"115;
%"TAP"
"1","(-1925,2950)","2","standard","I264";
;
CDS_LIB"standard"
BODY_TYPE"PLUMBING"
HDL_TAP"TRUE";
"B \NAC \NWC"1;
"S \NAC"
BN"12"139;
%"TAP"
"1","(-1675,2600)","2","standard","I265";
;
CDS_LIB"standard"
BODY_TYPE"PLUMBING"
HDL_TAP"TRUE";
"B \NAC \NWC"2;
"S \NAC"
BN"10"112;
%"TAP"
"1","(-1675,2800)","2","standard","I266";
;
CDS_LIB"standard"
BODY_TYPE"PLUMBING"
HDL_TAP"TRUE";
"B \NAC \NWC"2;
"S \NAC"
BN"11"113;
%"TAP"
"1","(-1675,3000)","2","standard","I267";
;
CDS_LIB"standard"
BODY_TYPE"PLUMBING"
HDL_TAP"TRUE";
"B \NAC \NWC"2;
"S \NAC"
BN"12"140;
%"TAP"
"1","(-1925,3150)","2","standard","I268";
;
CDS_LIB"standard"
BODY_TYPE"PLUMBING"
HDL_TAP"TRUE";
"B \NAC \NWC"1;
"S \NAC"
BN"13"141;
%"TAP"
"1","(-1925,3350)","2","standard","I269";
;
CDS_LIB"standard"
BODY_TYPE"PLUMBING"
HDL_TAP"TRUE";
"B \NAC \NWC"1;
"S \NAC"
BN"14"142;
%"TAP"
"1","(-1925,3550)","2","standard","I270";
;
CDS_LIB"standard"
BODY_TYPE"PLUMBING"
HDL_TAP"TRUE";
"B \NAC \NWC"1;
"S \NAC"
BN"15"144;
%"TAP"
"1","(-1675,3200)","2","standard","I271";
;
CDS_LIB"standard"
BODY_TYPE"PLUMBING"
HDL_TAP"TRUE";
"B \NAC \NWC"2;
"S \NAC"
BN"13"118;
%"TAP"
"1","(-1675,3400)","2","standard","I272";
;
CDS_LIB"standard"
BODY_TYPE"PLUMBING"
HDL_TAP"TRUE";
"B \NAC \NWC"2;
"S \NAC"
BN"14"143;
%"TAP"
"1","(-1675,3600)","2","standard","I273";
;
CDS_LIB"standard"
BODY_TYPE"PLUMBING"
HDL_TAP"TRUE";
"B \NAC \NWC"2;
"S \NAC"
BN"15"117;
%"Q_CAP_DIFFBUS"
"2","(-950,2150)","2","pure_quanta","I274";
;
LOCATION"C725"
$SEC"1"
CDS_SEC"1"
VALUE"DIFF BUS_0.22UF"
CDS_LMAN_SYM_OUTLINE"-25,50,25,-50"
CDS_LIB"pure_quanta"
PIN_NAMES_ROTATE"TRUE"
VOLTAGE"6.3V"
MATERIAL"X6S"
PACK_TYPE"C0201"
TOLERANCE"20%"
PART_NUMBER"SP_CH4221MEE01"
LOCATION"C725";
"2"
$PN"2"29;
"1"
$PN"1"125;
%"Q_CAP_DIFFBUS"
"2","(-950,2200)","2","pure_quanta","I275";
;
LOCATION"C724"
$SEC"1"
CDS_SEC"1"
VALUE"DIFF BUS_0.22UF"
CDS_LMAN_SYM_OUTLINE"-25,50,25,-50"
CDS_LIB"pure_quanta"
PIN_NAMES_ROTATE"TRUE"
VOLTAGE"6.3V"
MATERIAL"X6S"
PACK_TYPE"C0201"
TOLERANCE"20%"
PART_NUMBER"SP_CH4221MEE01"
LOCATION"C724";
"2"
$PN"2"116;
"1"
$PN"1"121;
%"Q_CAP_DIFFBUS"
"2","(-950,2400)","2","pure_quanta","I276";
;
LOCATION"C722"
$SEC"1"
CDS_SEC"1"
VALUE"DIFF BUS_0.22UF"
CDS_LIB"pure_quanta"
CDS_LMAN_SYM_OUTLINE"-25,50,25,-50"
PIN_NAMES_ROTATE"TRUE"
VOLTAGE"6.3V"
MATERIAL"X6S"
PACK_TYPE"C0201"
TOLERANCE"20%"
PART_NUMBER"SP_CH4221MEE01"
LOCATION"C722";
"2"
$PN"2"137;
"1"
$PN"1"123;
%"Q_CAP_DIFFBUS"
"2","(-950,2350)","2","pure_quanta","I277";
;
LOCATION"C723"
$SEC"1"
CDS_SEC"1"
VALUE"DIFF BUS_0.22UF"
CDS_LMAN_SYM_OUTLINE"-25,50,25,-50"
CDS_LIB"pure_quanta"
PIN_NAMES_ROTATE"TRUE"
VOLTAGE"6.3V"
MATERIAL"X6S"
PACK_TYPE"C0201"
TOLERANCE"20%"
PART_NUMBER"SP_CH4221MEE01"
LOCATION"C723";
"2"
$PN"2"114;
"1"
$PN"1"23;
%"Q_CAP_DIFFBUS"
"2","(-950,2550)","2","pure_quanta","I278";
;
LOCATION"C721"
$SEC"1"
CDS_SEC"1"
VALUE"DIFF BUS_0.22UF"
CDS_LMAN_SYM_OUTLINE"-25,50,25,-50"
CDS_LIB"pure_quanta"
PIN_NAMES_ROTATE"TRUE"
VOLTAGE"6.3V"
MATERIAL"X6S"
PACK_TYPE"C0201"
TOLERANCE"20%"
PART_NUMBER"SP_CH4221MEE01"
LOCATION"C721";
"2"
$PN"2"115;
"1"
$PN"1"124;
%"Q_CAP_DIFFBUS"
"2","(-950,2600)","2","pure_quanta","I279";
;
LOCATION"C720"
$SEC"1"
CDS_SEC"1"
VALUE"DIFF BUS_0.22UF"
CDS_LMAN_SYM_OUTLINE"-25,50,25,-50"
CDS_LIB"pure_quanta"
PIN_NAMES_ROTATE"TRUE"
VOLTAGE"6.3V"
MATERIAL"X6S"
PACK_TYPE"C0201"
TOLERANCE"20%"
PART_NUMBER"SP_CH4221MEE01"
LOCATION"C720";
"2"
$PN"2"112;
"1"
$PN"1"22;
%"Q_CAP_DIFFBUS"
"2","(-950,2750)","2","pure_quanta","I280";
;
LOCATION"C719"
$SEC"1"
CDS_SEC"1"
VALUE"DIFF BUS_0.22UF"
CDS_LIB"pure_quanta"
CDS_LMAN_SYM_OUTLINE"-25,50,25,-50"
PIN_NAMES_ROTATE"TRUE"
VOLTAGE"6.3V"
MATERIAL"X6S"
PACK_TYPE"C0201"
TOLERANCE"20%"
PART_NUMBER"SP_CH4221MEE01"
LOCATION"C719";
"2"
$PN"2"138;
"1"
$PN"1"21;
%"Q_CAP_DIFFBUS"
"2","(-950,2800)","2","pure_quanta","I281";
;
LOCATION"C718"
$SEC"1"
CDS_SEC"1"
VALUE"DIFF BUS_0.22UF"
CDS_LIB"pure_quanta"
CDS_LMAN_SYM_OUTLINE"-25,50,25,-50"
PIN_NAMES_ROTATE"TRUE"
VOLTAGE"6.3V"
MATERIAL"X6S"
PACK_TYPE"C0201"
TOLERANCE"20%"
PART_NUMBER"SP_CH4221MEE01"
LOCATION"C718";
"2"
$PN"2"113;
"1"
$PN"1"120;
%"Q_CAP_DIFFBUS"
"2","(-950,2950)","2","pure_quanta","I282";
;
LOCATION"C717"
$SEC"1"
CDS_SEC"1"
VALUE"DIFF BUS_0.22UF"
CDS_LMAN_SYM_OUTLINE"-25,50,25,-50"
CDS_LIB"pure_quanta"
PIN_NAMES_ROTATE"TRUE"
VOLTAGE"6.3V"
MATERIAL"X6S"
PACK_TYPE"C0201"
TOLERANCE"20%"
PART_NUMBER"SP_CH4221MEE01"
LOCATION"C717";
"2"
$PN"2"139;
"1"
$PN"1"119;
%"Q_CAP_DIFFBUS"
"2","(-950,3000)","2","pure_quanta","I283";
;
LOCATION"C716"
$SEC"1"
CDS_SEC"1"
VALUE"DIFF BUS_0.22UF"
CDS_LMAN_SYM_OUTLINE"-25,50,25,-50"
CDS_LIB"pure_quanta"
PIN_NAMES_ROTATE"TRUE"
VOLTAGE"6.3V"
MATERIAL"X6S"
PACK_TYPE"C0201"
TOLERANCE"20%"
PART_NUMBER"SP_CH4221MEE01"
LOCATION"C716";
"2"
$PN"2"140;
"1"
$PN"1"122;
%"TAP"
"1","(-400,2200)","0","standard","I284";
;
CDS_LIB"standard"
BODY_TYPE"PLUMBING"
HDL_TAP"TRUE";
"B \NAC \NWC"7;
"S \NAC"
BN"8"121;
%"TAP"
"1","(-400,2400)","0","standard","I285";
;
CDS_LIB"standard"
BODY_TYPE"PLUMBING"
HDL_TAP"TRUE";
"B \NAC \NWC"7;
"S \NAC"
BN"9"123;
%"TAP"
"1","(-200,2150)","0","standard","I286";
;
CDS_LIB"standard"
BODY_TYPE"PLUMBING"
HDL_TAP"TRUE";
"B \NAC \NWC"6;
"S \NAC"
BN"8"125;
%"TAP"
"1","(-200,2350)","0","standard","I287";
;
CDS_LIB"standard"
BODY_TYPE"PLUMBING"
HDL_TAP"TRUE";
"B \NAC \NWC"6;
"S \NAC"
BN"9"23;
%"TAP"
"1","(-400,2600)","0","standard","I288";
;
CDS_LIB"standard"
BODY_TYPE"PLUMBING"
HDL_TAP"TRUE";
"B \NAC \NWC"7;
"S \NAC"
BN"10"22;
%"TAP"
"1","(-400,3000)","0","standard","I289";
;
CDS_LIB"standard"
BODY_TYPE"PLUMBING"
HDL_TAP"TRUE";
"B \NAC \NWC"7;
"S \NAC"
BN"12"122;
%"TAP"
"1","(-400,2800)","0","standard","I290";
;
CDS_LIB"standard"
BODY_TYPE"PLUMBING"
HDL_TAP"TRUE";
"B \NAC \NWC"7;
"S \NAC"
BN"11"120;
%"TAP"
"1","(-200,2550)","0","standard","I291";
;
CDS_LIB"standard"
BODY_TYPE"PLUMBING"
HDL_TAP"TRUE";
"B \NAC \NWC"6;
"S \NAC"
BN"10"124;
%"TAP"
"1","(-200,2750)","0","standard","I292";
;
CDS_LIB"standard"
BODY_TYPE"PLUMBING"
HDL_TAP"TRUE";
"B \NAC \NWC"6;
"S \NAC"
BN"11"21;
%"TAP"
"1","(-200,2950)","0","standard","I293";
;
CDS_LIB"standard"
BODY_TYPE"PLUMBING"
HDL_TAP"TRUE";
"B \NAC \NWC"6;
"S \NAC"
BN"12"119;
%"Q_CAP_DIFFBUS"
"2","(-950,3150)","2","pure_quanta","I294";
;
LOCATION"C715"
$SEC"1"
CDS_SEC"1"
VALUE"DIFF BUS_0.22UF"
CDS_LMAN_SYM_OUTLINE"-25,50,25,-50"
CDS_LIB"pure_quanta"
PIN_NAMES_ROTATE"TRUE"
VOLTAGE"6.3V"
MATERIAL"X6S"
PACK_TYPE"C0201"
TOLERANCE"20%"
PART_NUMBER"SP_CH4221MEE01"
LOCATION"C715";
"2"
$PN"2"141;
"1"
$PN"1"131;
%"Q_CAP_DIFFBUS"
"2","(-950,3200)","2","pure_quanta","I295";
;
LOCATION"C714"
$SEC"1"
CDS_SEC"1"
VALUE"DIFF BUS_0.22UF"
CDS_LMAN_SYM_OUTLINE"-25,50,25,-50"
CDS_LIB"pure_quanta"
PIN_NAMES_ROTATE"TRUE"
VOLTAGE"6.3V"
MATERIAL"X6S"
PACK_TYPE"C0201"
TOLERANCE"20%"
PART_NUMBER"SP_CH4221MEE01"
LOCATION"C714";
"2"
$PN"2"118;
"1"
$PN"1"127;
%"Q_CAP_DIFFBUS"
"2","(-950,3400)","2","pure_quanta","I296";
;
LOCATION"C712"
$SEC"1"
CDS_SEC"1"
VALUE"DIFF BUS_0.22UF"
CDS_LMAN_SYM_OUTLINE"-25,50,25,-50"
CDS_LIB"pure_quanta"
PIN_NAMES_ROTATE"TRUE"
VOLTAGE"6.3V"
MATERIAL"X6S"
PACK_TYPE"C0201"
TOLERANCE"20%"
PART_NUMBER"SP_CH4221MEE01"
LOCATION"C712";
"2"
$PN"2"143;
"1"
$PN"1"126;
%"Q_CAP_DIFFBUS"
"2","(-950,3350)","2","pure_quanta","I297";
;
LOCATION"C713"
$SEC"1"
CDS_SEC"1"
VALUE"DIFF BUS_0.22UF"
CDS_LMAN_SYM_OUTLINE"-25,50,25,-50"
CDS_LIB"pure_quanta"
PIN_NAMES_ROTATE"TRUE"
VOLTAGE"6.3V"
MATERIAL"X6S"
PACK_TYPE"C0201"
TOLERANCE"20%"
PART_NUMBER"SP_CH4221MEE01"
LOCATION"C713";
"2"
$PN"2"142;
"1"
$PN"1"129;
%"Q_CAP_DIFFBUS"
"2","(-950,3550)","2","pure_quanta","I298";
;
LOCATION"C711"
$SEC"1"
CDS_SEC"1"
VALUE"DIFF BUS_0.22UF"
CDS_LMAN_SYM_OUTLINE"-25,50,25,-50"
CDS_LIB"pure_quanta"
PIN_NAMES_ROTATE"TRUE"
VOLTAGE"6.3V"
MATERIAL"X6S"
PACK_TYPE"C0201"
TOLERANCE"20%"
PART_NUMBER"SP_CH4221MEE01"
LOCATION"C711";
"2"
$PN"2"144;
"1"
$PN"1"130;
%"Q_CAP_DIFFBUS"
"2","(-950,3600)","2","pure_quanta","I299";
;
LOCATION"C710"
$SEC"1"
CDS_SEC"1"
VOLTAGE"6.3V"
TOLERANCE"20%"
VALUE"DIFF BUS_0.22UF"
PACK_TYPE"C0201"
MATERIAL"X6S"
CDS_LIB"pure_quanta"
CDS_LMAN_SYM_OUTLINE"-25,50,25,-50"
PIN_NAMES_ROTATE"TRUE"
PART_NUMBER"SP_CH4221MEE01"
LOCATION"C710";
"2"
$PN"2"117;
"1"
$PN"1"128;
%"TAP"
"1","(-400,3200)","0","standard","I300";
;
CDS_LIB"standard"
BODY_TYPE"PLUMBING"
HDL_TAP"TRUE";
"B \NAC \NWC"7;
"S \NAC"
BN"13"127;
%"TAP"
"1","(-400,3400)","0","standard","I301";
;
CDS_LIB"standard"
BODY_TYPE"PLUMBING"
HDL_TAP"TRUE";
"B \NAC \NWC"7;
"S \NAC"
BN"14"126;
%"TAP"
"1","(-200,3150)","0","standard","I302";
;
CDS_LIB"standard"
BODY_TYPE"PLUMBING"
HDL_TAP"TRUE";
"B \NAC \NWC"6;
"S \NAC"
BN"13"131;
%"TAP"
"1","(-200,3350)","0","standard","I303";
;
CDS_LIB"standard"
BODY_TYPE"PLUMBING"
HDL_TAP"TRUE";
"B \NAC \NWC"6;
"S \NAC"
BN"14"129;
%"TAP"
"1","(-200,3550)","0","standard","I304";
;
CDS_LIB"standard"
BODY_TYPE"PLUMBING"
HDL_TAP"TRUE";
"B \NAC \NWC"6;
"S \NAC"
BN"15"130;
%"TAP"
"1","(-400,3600)","0","standard","I305";
;
CDS_LIB"standard"
BODY_TYPE"PLUMBING"
HDL_TAP"TRUE";
"B \NAC \NWC"7;
"S \NAC"
BN"15"128;
%"TAP"
"1","(-200,975)","0","standard","I310";
;
CDS_LIB"standard"
BODY_TYPE"PLUMBING"
HDL_TAP"TRUE";
"B \NAC \NWC"5;
"S \NAC"
BN"4"132;
%"TAP"
"1","(-400,1225)","0","standard","I311";
;
CDS_LIB"standard"
BODY_TYPE"PLUMBING"
HDL_TAP"TRUE";
"B \NAC \NWC"4;
"S \NAC"
BN"5"111;
%"Q_CAP_DIFFBUS"
"2","(-950,1625)","2","pure_quanta","I312";
;
LOCATION"C726"
$SEC"1"
CDS_SEC"1"
VALUE"DIFF BUS_0.22UF"
PIN_NAMES_ROTATE"TRUE"
CDS_LMAN_SYM_OUTLINE"-25,50,25,-50"
CDS_LIB"pure_quanta"
VOLTAGE"6.3V"
MATERIAL"X6S"
PACK_TYPE"C0201"
TOLERANCE"20%"
PART_NUMBER"SP_CH4221MEE01"
LOCATION"C726";
"2"
$PN"2"96;
"1"
$PN"1"110;
END.
